(kicad_pcb
	(version 20260206)
	(generator "pcbnew")
	(generator_version "10.0")
	(general
		(thickness 1.6)
		(legacy_teardrops no)
	)
	(paper "A4")
	(title_block
		(title "12092022_DA0F0TYB4D0_F0T_Panel_BD_Front_D_brd_v02_OCP.brd")
		(comment 1 "Grand Teton / footprints 50-56 of 128")
	)
	(layers
		(0 "F.Cu" signal "TOP")
		(4 "In1.Cu" signal "GND")
		(6 "In2.Cu" signal "GND1")
		(2 "B.Cu" signal "BOTTOM")
		(9 "F.Adhes" user "F.Adhesive")
		(11 "B.Adhes" user "B.Adhesive")
		(13 "F.Paste" user "Package Geometry/Pastemask Top")
		(15 "B.Paste" user "Package Geometry/Pastemask Bottom")
		(5 "F.SilkS" user "Ref Des/Silkscreen Top")
		(7 "B.SilkS" user "Ref Des/Silkscreen Bottom")
		(1 "F.Mask" user "Board Geometry/Soldermask Top")
		(3 "B.Mask" user "Board Geometry/Soldermask Bottom")
		(17 "Dwgs.User" user "User.Drawings")
		(19 "Cmts.User" user "User.Comments")
		(21 "Eco1.User" user "User.Eco1")
		(23 "Eco2.User" user "User.Eco2")
		(25 "Edge.Cuts" user "Board Geometry/Outline")
		(27 "Margin" user)
		(31 "F.CrtYd" user "Package Geometry/Place Bound Top")
		(29 "B.CrtYd" user "Package Geometry/Place Bound Bottom")
		(35 "F.Fab" user "Ref Des/Assembly Top")
		(33 "B.Fab" user "Ref Des/Assembly Bottom")
	)
	(footprint ""
		(layer "F.Cu")
		(at 13.462 -21.209)
		(property "Reference" "R43"
			(at 0.635 1.42367 0)
			(unlocked yes)
			(layer "F.SilkS")
			(effects
				(font
					(size 0.7874 0.5842)
					(thickness 0.1524)
				)
			)
		)
		(property "Value" ""
			(at 0 0 0)
			(layer "F.Fab")
			(effects
				(font
					(size 1.27 1.27)
				)
			)
		)
		(duplicate_pad_numbers_are_jumpers no)
		(fp_line
			(start -0.7874 -0.4064)
			(end 0.7874 -0.4064)
			(stroke
				(width 0.1524)
				(type default)
			)
			(layer "F.SilkS")
		)
		(fp_line
			(start -0.7874 0.4064)
			(end -0.7874 -0.4064)
			(stroke
				(width 0.1524)
				(type default)
			)
			(layer "F.SilkS")
		)
		(fp_line
			(start 0.7874 -0.4064)
			(end 0.7874 0.4064)
			(stroke
				(width 0.1524)
				(type default)
			)
			(layer "F.SilkS")
		)
		(fp_line
			(start 0.7874 0.4064)
			(end -0.7874 0.4064)
			(stroke
				(width 0.1524)
				(type default)
			)
			(layer "F.SilkS")
		)
		(fp_line
			(start -0.67945 -0.305054)
			(end -0.12065 -0.305054)
			(stroke
				(width 0.1)
				(type default)
			)
			(layer "F.Fab")
		)
		(fp_line
			(start -0.67945 0.3048)
			(end -0.67945 -0.305054)
			(stroke
				(width 0.1)
				(type default)
			)
			(layer "F.Fab")
		)
		(fp_line
			(start -0.12065 -0.305054)
			(end -0.12065 -0.2794)
			(stroke
				(width 0.1)
				(type default)
			)
			(layer "F.Fab")
		)
		(fp_line
			(start -0.12065 -0.2794)
			(end 0.12065 -0.2794)
			(stroke
				(width 0.1)
				(type default)
			)
			(layer "F.Fab")
		)
		(fp_line
			(start -0.12065 0.2794)
			(end -0.12065 0.3048)
			(stroke
				(width 0.1)
				(type default)
			)
			(layer "F.Fab")
		)
		(fp_line
			(start -0.12065 0.3048)
			(end -0.67945 0.3048)
			(stroke
				(width 0.1)
				(type default)
			)
			(layer "F.Fab")
		)
		(fp_line
			(start 0.120396 0.2794)
			(end -0.12065 0.2794)
			(stroke
				(width 0.1)
				(type default)
			)
			(layer "F.Fab")
		)
		(fp_line
			(start 0.120396 0.3048)
			(end 0.120396 0.2794)
			(stroke
				(width 0.1)
				(type default)
			)
			(layer "F.Fab")
		)
		(fp_line
			(start 0.12065 -0.3048)
			(end 0.67945 -0.3048)
			(stroke
				(width 0.1)
				(type default)
			)
			(layer "F.Fab")
		)
		(fp_line
			(start 0.12065 -0.2794)
			(end 0.12065 -0.3048)
			(stroke
				(width 0.1)
				(type default)
			)
			(layer "F.Fab")
		)
		(fp_line
			(start 0.67945 -0.3048)
			(end 0.67945 0.3048)
			(stroke
				(width 0.1)
				(type default)
			)
			(layer "F.Fab")
		)
		(fp_line
			(start 0.67945 0.3048)
			(end 0.120396 0.3048)
			(stroke
				(width 0.1)
				(type default)
			)
			(layer "F.Fab")
		)
		(pad "1" smd circle
			(at -0.40005 0)
			(size 0 0)
			(layers "F.Cu" "F.Mask" "F.Paste")
			(net "P5V_STBY")
		)
		(pad "2" smd circle
			(at 0.40005 0)
			(size 0 0)
			(layers "F.Cu" "F.Mask" "F.Paste")
			(net "PRSNT_DBV2_USB")
		)
	)
	(footprint ""
		(layer "F.Cu")
		(at 5.969 -57.277)
		(property "Reference" "R23"
			(at -2.794 0.40767 0)
			(unlocked yes)
			(layer "F.SilkS")
			(effects
				(font
					(size 0.7874 0.5842)
					(thickness 0.1524)
				)
			)
		)
		(property "Value" ""
			(at 0 0 0)
			(layer "F.Fab")
			(effects
				(font
					(size 1.27 1.27)
				)
			)
		)
		(duplicate_pad_numbers_are_jumpers no)
		(fp_line
			(start -0.7874 -0.4064)
			(end 0.7874 -0.4064)
			(stroke
				(width 0.1524)
				(type default)
			)
			(layer "F.SilkS")
		)
		(fp_line
			(start -0.7874 0.4064)
			(end -0.7874 -0.4064)
			(stroke
				(width 0.1524)
				(type default)
			)
			(layer "F.SilkS")
		)
		(fp_line
			(start 0.7874 -0.4064)
			(end 0.7874 0.4064)
			(stroke
				(width 0.1524)
				(type default)
			)
			(layer "F.SilkS")
		)
		(fp_line
			(start 0.7874 0.4064)
			(end -0.7874 0.4064)
			(stroke
				(width 0.1524)
				(type default)
			)
			(layer "F.SilkS")
		)
		(fp_line
			(start -0.67945 -0.305054)
			(end -0.12065 -0.305054)
			(stroke
				(width 0.1)
				(type default)
			)
			(layer "F.Fab")
		)
		(fp_line
			(start -0.67945 0.3048)
			(end -0.67945 -0.305054)
			(stroke
				(width 0.1)
				(type default)
			)
			(layer "F.Fab")
		)
		(fp_line
			(start -0.12065 -0.305054)
			(end -0.12065 -0.2794)
			(stroke
				(width 0.1)
				(type default)
			)
			(layer "F.Fab")
		)
		(fp_line
			(start -0.12065 -0.2794)
			(end 0.12065 -0.2794)
			(stroke
				(width 0.1)
				(type default)
			)
			(layer "F.Fab")
		)
		(fp_line
			(start -0.12065 0.2794)
			(end -0.12065 0.3048)
			(stroke
				(width 0.1)
				(type default)
			)
			(layer "F.Fab")
		)
		(fp_line
			(start -0.12065 0.3048)
			(end -0.67945 0.3048)
			(stroke
				(width 0.1)
				(type default)
			)
			(layer "F.Fab")
		)
		(fp_line
			(start 0.120396 0.2794)
			(end -0.12065 0.2794)
			(stroke
				(width 0.1)
				(type default)
			)
			(layer "F.Fab")
		)
		(fp_line
			(start 0.120396 0.3048)
			(end 0.120396 0.2794)
			(stroke
				(width 0.1)
				(type default)
			)
			(layer "F.Fab")
		)
		(fp_line
			(start 0.12065 -0.3048)
			(end 0.67945 -0.3048)
			(stroke
				(width 0.1)
				(type default)
			)
			(layer "F.Fab")
		)
		(fp_line
			(start 0.12065 -0.2794)
			(end 0.12065 -0.3048)
			(stroke
				(width 0.1)
				(type default)
			)
			(layer "F.Fab")
		)
		(fp_line
			(start 0.67945 -0.3048)
			(end 0.67945 0.3048)
			(stroke
				(width 0.1)
				(type default)
			)
			(layer "F.Fab")
		)
		(fp_line
			(start 0.67945 0.3048)
			(end 0.120396 0.3048)
			(stroke
				(width 0.1)
				(type default)
			)
			(layer "F.Fab")
		)
		(pad "1" smd circle
			(at -0.40005 0)
			(size 0 0)
			(layers "F.Cu" "F.Mask" "F.Paste")
			(net "P3V3_STBY")
		)
		(pad "2" smd circle
			(at 0.40005 0)
			(size 0 0)
			(layers "F.Cu" "F.Mask" "F.Paste")
			(net "REV_ID<2>")
		)
	)
	(footprint ""
		(layer "F.Cu")
		(at 15.875 -46.101 180)
		(property "Reference" "R60"
			(at -2.54 -0.02667 0)
			(unlocked yes)
			(layer "F.SilkS")
			(effects
				(font
					(size 0.7874 0.5842)
					(thickness 0.1524)
				)
			)
		)
		(property "Value" ""
			(at 0 0 180)
			(layer "F.Fab")
			(effects
				(font
					(size 1.27 1.27)
				)
			)
		)
		(duplicate_pad_numbers_are_jumpers no)
		(fp_line
			(start 0.7874 0.4064)
			(end -0.7874 0.4064)
			(stroke
				(width 0.1524)
				(type default)
			)
			(layer "F.SilkS")
		)
		(fp_line
			(start 0.7874 -0.4064)
			(end 0.7874 0.4064)
			(stroke
				(width 0.1524)
				(type default)
			)
			(layer "F.SilkS")
		)
		(fp_line
			(start -0.7874 0.4064)
			(end -0.7874 -0.4064)
			(stroke
				(width 0.1524)
				(type default)
			)
			(layer "F.SilkS")
		)
		(fp_line
			(start -0.7874 -0.4064)
			(end 0.7874 -0.4064)
			(stroke
				(width 0.1524)
				(type default)
			)
			(layer "F.SilkS")
		)
		(fp_line
			(start 0.67945 0.3048)
			(end 0.120396 0.3048)
			(stroke
				(width 0.1)
				(type default)
			)
			(layer "F.Fab")
		)
		(fp_line
			(start 0.67945 -0.3048)
			(end 0.67945 0.3048)
			(stroke
				(width 0.1)
				(type default)
			)
			(layer "F.Fab")
		)
		(fp_line
			(start 0.12065 -0.2794)
			(end 0.12065 -0.3048)
			(stroke
				(width 0.1)
				(type default)
			)
			(layer "F.Fab")
		)
		(fp_line
			(start 0.12065 -0.3048)
			(end 0.67945 -0.3048)
			(stroke
				(width 0.1)
				(type default)
			)
			(layer "F.Fab")
		)
		(fp_line
			(start 0.120396 0.3048)
			(end 0.120396 0.2794)
			(stroke
				(width 0.1)
				(type default)
			)
			(layer "F.Fab")
		)
		(fp_line
			(start 0.120396 0.2794)
			(end -0.12065 0.2794)
			(stroke
				(width 0.1)
				(type default)
			)
			(layer "F.Fab")
		)
		(fp_line
			(start -0.12065 0.3048)
			(end -0.67945 0.3048)
			(stroke
				(width 0.1)
				(type default)
			)
			(layer "F.Fab")
		)
		(fp_line
			(start -0.12065 0.2794)
			(end -0.12065 0.3048)
			(stroke
				(width 0.1)
				(type default)
			)
			(layer "F.Fab")
		)
		(fp_line
			(start -0.12065 -0.2794)
			(end 0.12065 -0.2794)
			(stroke
				(width 0.1)
				(type default)
			)
			(layer "F.Fab")
		)
		(fp_line
			(start -0.12065 -0.305054)
			(end -0.12065 -0.2794)
			(stroke
				(width 0.1)
				(type default)
			)
			(layer "F.Fab")
		)
		(fp_line
			(start -0.67945 0.3048)
			(end -0.67945 -0.305054)
			(stroke
				(width 0.1)
				(type default)
			)
			(layer "F.Fab")
		)
		(fp_line
			(start -0.67945 -0.305054)
			(end -0.12065 -0.305054)
			(stroke
				(width 0.1)
				(type default)
			)
			(layer "F.Fab")
		)
		(pad "1" smd circle
			(at -0.40005 0 180)
			(size 0 0)
			(layers "F.Cu" "F.Mask" "F.Paste")
			(net "SMB_SDA")
		)
		(pad "2" smd circle
			(at 0.40005 0 180)
			(size 0 0)
			(layers "F.Cu" "F.Mask" "F.Paste")
			(net "SMB_FRU_SDA")
		)
	)
	(footprint ""
		(layer "F.Cu")
		(at 3.937 -48.768 180)
		(property "Reference" "R62"
			(at 2.413 -0.15367 0)
			(unlocked yes)
			(layer "F.SilkS")
			(effects
				(font
					(size 0.7874 0.5842)
					(thickness 0.1524)
				)
			)
		)
		(property "Value" ""
			(at 0 0 180)
			(layer "F.Fab")
			(effects
				(font
					(size 1.27 1.27)
				)
			)
		)
		(duplicate_pad_numbers_are_jumpers no)
		(fp_line
			(start 0.7874 0.4064)
			(end -0.7874 0.4064)
			(stroke
				(width 0.1524)
				(type default)
			)
			(layer "F.SilkS")
		)
		(fp_line
			(start 0.7874 -0.4064)
			(end 0.7874 0.4064)
			(stroke
				(width 0.1524)
				(type default)
			)
			(layer "F.SilkS")
		)
		(fp_line
			(start -0.7874 0.4064)
			(end -0.7874 -0.4064)
			(stroke
				(width 0.1524)
				(type default)
			)
			(layer "F.SilkS")
		)
		(fp_line
			(start -0.7874 -0.4064)
			(end 0.7874 -0.4064)
			(stroke
				(width 0.1524)
				(type default)
			)
			(layer "F.SilkS")
		)
		(fp_line
			(start 0.67945 0.3048)
			(end 0.120396 0.3048)
			(stroke
				(width 0.1)
				(type default)
			)
			(layer "F.Fab")
		)
		(fp_line
			(start 0.67945 -0.3048)
			(end 0.67945 0.3048)
			(stroke
				(width 0.1)
				(type default)
			)
			(layer "F.Fab")
		)
		(fp_line
			(start 0.12065 -0.2794)
			(end 0.12065 -0.3048)
			(stroke
				(width 0.1)
				(type default)
			)
			(layer "F.Fab")
		)
		(fp_line
			(start 0.12065 -0.3048)
			(end 0.67945 -0.3048)
			(stroke
				(width 0.1)
				(type default)
			)
			(layer "F.Fab")
		)
		(fp_line
			(start 0.120396 0.3048)
			(end 0.120396 0.2794)
			(stroke
				(width 0.1)
				(type default)
			)
			(layer "F.Fab")
		)
		(fp_line
			(start 0.120396 0.2794)
			(end -0.12065 0.2794)
			(stroke
				(width 0.1)
				(type default)
			)
			(layer "F.Fab")
		)
		(fp_line
			(start -0.12065 0.3048)
			(end -0.67945 0.3048)
			(stroke
				(width 0.1)
				(type default)
			)
			(layer "F.Fab")
		)
		(fp_line
			(start -0.12065 0.2794)
			(end -0.12065 0.3048)
			(stroke
				(width 0.1)
				(type default)
			)
			(layer "F.Fab")
		)
		(fp_line
			(start -0.12065 -0.2794)
			(end 0.12065 -0.2794)
			(stroke
				(width 0.1)
				(type default)
			)
			(layer "F.Fab")
		)
		(fp_line
			(start -0.12065 -0.305054)
			(end -0.12065 -0.2794)
			(stroke
				(width 0.1)
				(type default)
			)
			(layer "F.Fab")
		)
		(fp_line
			(start -0.67945 0.3048)
			(end -0.67945 -0.305054)
			(stroke
				(width 0.1)
				(type default)
			)
			(layer "F.Fab")
		)
		(fp_line
			(start -0.67945 -0.305054)
			(end -0.12065 -0.305054)
			(stroke
				(width 0.1)
				(type default)
			)
			(layer "F.Fab")
		)
		(pad "1" smd circle
			(at -0.40005 0 180)
			(size 0 0)
			(layers "F.Cu" "F.Mask" "F.Paste")
			(net "PD_FRU_A1")
		)
		(pad "2" smd circle
			(at 0.40005 0 180)
			(size 0 0)
			(layers "F.Cu" "F.Mask" "F.Paste")
			(net "GND")
		)
	)
	(footprint ""
		(layer "F.Cu")
		(at 35.941 -30.607)
		(property "Reference" "C10"
			(at 0.762 -6.19633 0)
			(unlocked yes)
			(layer "F.SilkS")
			(effects
				(font
					(size 0.7874 0.5842)
					(thickness 0.1524)
				)
				(justify left)
			)
		)
		(property "Value" ""
			(at 0 0 0)
			(layer "F.Fab")
			(effects
				(font
					(size 1.27 1.27)
				)
			)
		)
		(duplicate_pad_numbers_are_jumpers no)
		(fp_line
			(start -1.524 -0.762)
			(end 1.524 -0.762)
			(stroke
				(width 0.1524)
				(type default)
			)
			(layer "F.SilkS")
		)
		(fp_line
			(start -1.524 0.762)
			(end -1.524 -0.762)
			(stroke
				(width 0.1524)
				(type default)
			)
			(layer "F.SilkS")
		)
		(fp_line
			(start 1.524 -0.762)
			(end 1.524 0.762)
			(stroke
				(width 0.1524)
				(type default)
			)
			(layer "F.SilkS")
		)
		(fp_line
			(start 1.524 0.762)
			(end -1.524 0.762)
			(stroke
				(width 0.1524)
				(type default)
			)
			(layer "F.SilkS")
		)
		(fp_line
			(start -1.1049 -0.724916)
			(end -1.1049 0.724916)
			(stroke
				(width 0.1)
				(type default)
			)
			(layer "F.Fab")
		)
		(fp_line
			(start -1.1049 0.724916)
			(end 1.1049 0.724916)
			(stroke
				(width 0.1)
				(type default)
			)
			(layer "F.Fab")
		)
		(fp_line
			(start 1.1049 -0.724916)
			(end -1.1049 -0.724916)
			(stroke
				(width 0.1)
				(type default)
			)
			(layer "F.Fab")
		)
		(fp_line
			(start 1.1049 0.724916)
			(end 1.1049 -0.724916)
			(stroke
				(width 0.1)
				(type default)
			)
			(layer "F.Fab")
		)
		(pad "1" smd rect
			(at -0.889 0 180)
			(size 1.016 1.27)
			(layers "F.Cu" "F.Mask" "F.Paste")
			(net "P5V_STBY_DEBUG")
		)
		(pad "2" smd rect
			(at 0.889 0 180)
			(size 1.016 1.27)
			(layers "F.Cu" "F.Mask" "F.Paste")
			(net "GND")
		)
	)
	(footprint ""
		(layer "F.Cu")
		(at 5.969 -54.229 180)
		(property "Reference" "R26"
			(at 2.794 -0.40767 0)
			(unlocked yes)
			(layer "F.SilkS")
			(effects
				(font
					(size 0.7874 0.5842)
					(thickness 0.1524)
				)
			)
		)
		(property "Value" ""
			(at 0 0 180)
			(layer "F.Fab")
			(effects
				(font
					(size 1.27 1.27)
				)
			)
		)
		(duplicate_pad_numbers_are_jumpers no)
		(fp_line
			(start 0.7874 0.4064)
			(end -0.7874 0.4064)
			(stroke
				(width 0.1524)
				(type default)
			)
			(layer "F.SilkS")
		)
		(fp_line
			(start 0.7874 -0.4064)
			(end 0.7874 0.4064)
			(stroke
				(width 0.1524)
				(type default)
			)
			(layer "F.SilkS")
		)
		(fp_line
			(start -0.7874 0.4064)
			(end -0.7874 -0.4064)
			(stroke
				(width 0.1524)
				(type default)
			)
			(layer "F.SilkS")
		)
		(fp_line
			(start -0.7874 -0.4064)
			(end 0.7874 -0.4064)
			(stroke
				(width 0.1524)
				(type default)
			)
			(layer "F.SilkS")
		)
		(fp_line
			(start 0.67945 0.3048)
			(end 0.120396 0.3048)
			(stroke
				(width 0.1)
				(type default)
			)
			(layer "F.Fab")
		)
		(fp_line
			(start 0.67945 -0.3048)
			(end 0.67945 0.3048)
			(stroke
				(width 0.1)
				(type default)
			)
			(layer "F.Fab")
		)
		(fp_line
			(start 0.12065 -0.2794)
			(end 0.12065 -0.3048)
			(stroke
				(width 0.1)
				(type default)
			)
			(layer "F.Fab")
		)
		(fp_line
			(start 0.12065 -0.3048)
			(end 0.67945 -0.3048)
			(stroke
				(width 0.1)
				(type default)
			)
			(layer "F.Fab")
		)
		(fp_line
			(start 0.120396 0.3048)
			(end 0.120396 0.2794)
			(stroke
				(width 0.1)
				(type default)
			)
			(layer "F.Fab")
		)
		(fp_line
			(start 0.120396 0.2794)
			(end -0.12065 0.2794)
			(stroke
				(width 0.1)
				(type default)
			)
			(layer "F.Fab")
		)
		(fp_line
			(start -0.12065 0.3048)
			(end -0.67945 0.3048)
			(stroke
				(width 0.1)
				(type default)
			)
			(layer "F.Fab")
		)
		(fp_line
			(start -0.12065 0.2794)
			(end -0.12065 0.3048)
			(stroke
				(width 0.1)
				(type default)
			)
			(layer "F.Fab")
		)
		(fp_line
			(start -0.12065 -0.2794)
			(end 0.12065 -0.2794)
			(stroke
				(width 0.1)
				(type default)
			)
			(layer "F.Fab")
		)
		(fp_line
			(start -0.12065 -0.305054)
			(end -0.12065 -0.2794)
			(stroke
				(width 0.1)
				(type default)
			)
			(layer "F.Fab")
		)
		(fp_line
			(start -0.67945 0.3048)
			(end -0.67945 -0.305054)
			(stroke
				(width 0.1)
				(type default)
			)
			(layer "F.Fab")
		)
		(fp_line
			(start -0.67945 -0.305054)
			(end -0.12065 -0.305054)
			(stroke
				(width 0.1)
				(type default)
			)
			(layer "F.Fab")
		)
		(pad "1" smd circle
			(at -0.40005 0 180)
			(size 0 0)
			(layers "F.Cu" "F.Mask" "F.Paste")
			(net "REV_ID<0>")
		)
		(pad "2" smd circle
			(at 0.40005 0 180)
			(size 0 0)
			(layers "F.Cu" "F.Mask" "F.Paste")
			(net "GND")
		)
	)
	(footprint ""
		(layer "F.Cu")
		(at 32.034734 -23.797768 -90)
		(property "Reference" "R52"
			(at 0.937768 -1.011936 90)
			(unlocked yes)
			(layer "F.SilkS")
			(effects
				(font
					(size 0.7874 0.5842)
					(thickness 0.1524)
				)
				(justify left)
			)
		)
		(property "Value" ""
			(at 0 0 270)
			(layer "F.Fab")
			(effects
				(font
					(size 1.27 1.27)
				)
			)
		)
		(duplicate_pad_numbers_are_jumpers no)
		(fp_line
			(start -0.7874 0.4064)
			(end -0.7874 -0.4064)
			(stroke
				(width 0.1524)
				(type default)
			)
			(layer "F.SilkS")
		)
		(fp_line
			(start 0.7874 0.4064)
			(end -0.7874 0.4064)
			(stroke
				(width 0.1524)
				(type default)
			)
			(layer "F.SilkS")
		)
		(fp_line
			(start -0.7874 -0.4064)
			(end 0.7874 -0.4064)
			(stroke
				(width 0.1524)
				(type default)
			)
			(layer "F.SilkS")
		)
		(fp_line
			(start 0.7874 -0.4064)
			(end 0.7874 0.4064)
			(stroke
				(width 0.1524)
				(type default)
			)
			(layer "F.SilkS")
		)
		(fp_line
			(start -0.67945 0.3048)
			(end -0.67945 -0.305054)
			(stroke
				(width 0.1)
				(type default)
			)
			(layer "F.Fab")
		)
		(fp_line
			(start -0.12065 0.3048)
			(end -0.67945 0.3048)
			(stroke
				(width 0.1)
				(type default)
			)
			(layer "F.Fab")
		)
		(fp_line
			(start 0.120396 0.3048)
			(end 0.120396 0.2794)
			(stroke
				(width 0.1)
				(type default)
			)
			(layer "F.Fab")
		)
		(fp_line
			(start 0.67945 0.3048)
			(end 0.120396 0.3048)
			(stroke
				(width 0.1)
				(type default)
			)
			(layer "F.Fab")
		)
		(fp_line
			(start -0.12065 0.2794)
			(end -0.12065 0.3048)
			(stroke
				(width 0.1)
				(type default)
			)
			(layer "F.Fab")
		)
		(fp_line
			(start 0.120396 0.2794)
			(end -0.12065 0.2794)
			(stroke
				(width 0.1)
				(type default)
			)
			(layer "F.Fab")
		)
		(fp_line
			(start -0.12065 -0.2794)
			(end 0.12065 -0.2794)
			(stroke
				(width 0.1)
				(type default)
			)
			(layer "F.Fab")
		)
		(fp_line
			(start 0.12065 -0.2794)
			(end 0.12065 -0.3048)
			(stroke
				(width 0.1)
				(type default)
			)
			(layer "F.Fab")
		)
		(fp_line
			(start 0.12065 -0.3048)
			(end 0.67945 -0.3048)
			(stroke
				(width 0.1)
				(type default)
			)
			(layer "F.Fab")
		)
		(fp_line
			(start 0.67945 -0.3048)
			(end 0.67945 0.3048)
			(stroke
				(width 0.1)
				(type default)
			)
			(layer "F.Fab")
		)
		(fp_line
			(start -0.67945 -0.305054)
			(end -0.12065 -0.305054)
			(stroke
				(width 0.1)
				(type default)
			)
			(layer "F.Fab")
		)
		(fp_line
			(start -0.12065 -0.305054)
			(end -0.12065 -0.2794)
			(stroke
				(width 0.1)
				(type default)
			)
			(layer "F.Fab")
		)
		(pad "1" smd rect
			(at -0.40005 0 90)
			(size 0.4572 0.508)
			(layers "F.Cu" "F.Mask" "F.Paste")
			(net "USB2_DP")
		)
		(pad "2" smd rect
			(at 0.40005 0 90)
			(size 0.4572 0.508)
			(layers "F.Cu" "F.Mask" "F.Paste")
			(net "USB2_DEBUG_DP")
		)
	)
)
